# S9S_MB_2U (Grand Teton) — schematic netlist excerpt (pin names and nets, part order shuffled) for the footprints in the layout excerpt that follows; sources: Cadence DE-HDL packaged netlist, KiCad conversion of 03242023_DA0F0TMBIJ0_F0T_Motherboard_J_brd_V01_OCP.brd

R3533  Q_RES  33.2 1% CHIP  pkg 0402LF  page 194 : A = SMB_E1S_3V3AUX_ISO_SCL_R ; B = SMB_E1S_3V3AUX_ISO_SCL
R2974  Q_RES  10K 1% CHIP  pkg 0402LF  page 195 : A = P1V05_PCH_AUX ; B = FAB_REV_ID1

(kicad_pcb
	(version 20260206)
	(generator "pcbnew")
	(generator_version "10.0")
	(general
		(thickness 1.6)
		(legacy_teardrops no)
	)
	(paper "A4")
	(title_block
		(title "03242023_DA0F0TMBIJ0_F0T_Motherboard_J_brd_V01_OCP.brd")
		(comment 1 "Grand Teton / footprints 765-766 of 6105")
	)
	(layers
		(0 "F.Cu" signal "TOP")
		(4 "In1.Cu" signal "GND")
		(6 "In2.Cu" signal "IN1")
		(8 "In3.Cu" signal "GND1")
		(10 "In4.Cu" signal "IN2")
		(12 "In5.Cu" signal "GND2")
		(14 "In6.Cu" signal "IN3")
		(16 "In7.Cu" signal "GND3")
		(18 "In8.Cu" signal "VCC")
		(20 "In9.Cu" signal "VCC1")
		(22 "In10.Cu" signal "GND4")
		(24 "In11.Cu" signal "IN4")
		(26 "In12.Cu" signal "GND5")
		(28 "In13.Cu" signal "IN5")
		(30 "In14.Cu" signal "GND6")
		(32 "In15.Cu" signal "IN6")
		(34 "In16.Cu" signal "GND7")
		(2 "B.Cu" signal "BOTTOM")
		(9 "F.Adhes" user "F.Adhesive")
		(11 "B.Adhes" user "B.Adhesive")
		(13 "F.Paste" user "Package Geometry/Pastemask Top")
		(15 "B.Paste" user "Package Geometry/Pastemask Bottom")
		(5 "F.SilkS" user "Ref Des/Silkscreen Top")
		(7 "B.SilkS" user "Ref Des/Silkscreen Bottom")
		(1 "F.Mask" user "Board Geometry/Soldermask Top")
		(3 "B.Mask" user "Board Geometry/Soldermask Bottom")
		(17 "Dwgs.User" user "User.Drawings")
		(19 "Cmts.User" user "User.Comments")
		(21 "Eco1.User" user "User.Eco1")
		(23 "Eco2.User" user "User.Eco2")
		(25 "Edge.Cuts" user "Board Geometry/Outline")
		(27 "Margin" user)
		(31 "F.CrtYd" user "Package Geometry/Place Bound Top")
		(29 "B.CrtYd" user "Package Geometry/Place Bound Bottom")
		(35 "F.Fab" user "Ref Des/Assembly Top")
		(33 "B.Fab" user "Ref Des/Assembly Bottom")
	)
	(footprint ""
		(layer "F.Cu")
		(at 223.70288 -43.525948)
		(property "Reference" "R3533"
			(at 0 0 0)
			(layer "F.SilkS")
			(hide yes)
			(effects
				(font
					(size 1.27 1.27)
				)
			)
		)
		(property "Value" ""
			(at 0 0 0)
			(layer "F.Fab")
			(effects
				(font
					(size 1.27 1.27)
				)
			)
		)
		(duplicate_pad_numbers_are_jumpers no)
		(fp_line
			(start -0.7874 -0.4064)
			(end 0.7874 -0.4064)
			(stroke
				(width 0.1524)
				(type default)
			)
			(layer "F.SilkS")
		)
		(fp_line
			(start -0.7874 0.4064)
			(end -0.7874 -0.4064)
			(stroke
				(width 0.1524)
				(type default)
			)
			(layer "F.SilkS")
		)
		(fp_line
			(start 0.7874 -0.4064)
			(end 0.7874 0.4064)
			(stroke
				(width 0.1524)
				(type default)
			)
			(layer "F.SilkS")
		)
		(fp_line
			(start 0.7874 0.4064)
			(end -0.7874 0.4064)
			(stroke
				(width 0.1524)
				(type default)
			)
			(layer "F.SilkS")
		)
		(fp_line
			(start -0.67945 -0.305054)
			(end -0.12065 -0.305054)
			(stroke
				(width 0.1)
				(type default)
			)
			(layer "F.Fab")
		)
		(fp_line
			(start -0.67945 0.3048)
			(end -0.67945 -0.305054)
			(stroke
				(width 0.1)
				(type default)
			)
			(layer "F.Fab")
		)
		(fp_line
			(start -0.12065 -0.305054)
			(end -0.12065 -0.2794)
			(stroke
				(width 0.1)
				(type default)
			)
			(layer "F.Fab")
		)
		(fp_line
			(start -0.12065 -0.2794)
			(end 0.12065 -0.2794)
			(stroke
				(width 0.1)
				(type default)
			)
			(layer "F.Fab")
		)
		(fp_line
			(start -0.12065 0.2794)
			(end -0.12065 0.3048)
			(stroke
				(width 0.1)
				(type default)
			)
			(layer "F.Fab")
		)
		(fp_line
			(start -0.12065 0.3048)
			(end -0.67945 0.3048)
			(stroke
				(width 0.1)
				(type default)
			)
			(layer "F.Fab")
		)
		(fp_line
			(start 0.120396 0.2794)
			(end -0.12065 0.2794)
			(stroke
				(width 0.1)
				(type default)
			)
			(layer "F.Fab")
		)
		(fp_line
			(start 0.120396 0.3048)
			(end 0.120396 0.2794)
			(stroke
				(width 0.1)
				(type default)
			)
			(layer "F.Fab")
		)
		(fp_line
			(start 0.12065 -0.3048)
			(end 0.67945 -0.3048)
			(stroke
				(width 0.1)
				(type default)
			)
			(layer "F.Fab")
		)
		(fp_line
			(start 0.12065 -0.2794)
			(end 0.12065 -0.3048)
			(stroke
				(width 0.1)
				(type default)
			)
			(layer "F.Fab")
		)
		(fp_line
			(start 0.67945 -0.3048)
			(end 0.67945 0.3048)
			(stroke
				(width 0.1)
				(type default)
			)
			(layer "F.Fab")
		)
		(fp_line
			(start 0.67945 0.3048)
			(end 0.120396 0.3048)
			(stroke
				(width 0.1)
				(type default)
			)
			(layer "F.Fab")
		)
		(pad "1" smd circle
			(at -0.40005 0)
			(size 0 0)
			(layers "F.Cu" "F.Mask" "F.Paste")
			(net "SMB_E1S_3V3AUX_ISO_SCL_R")
		)
		(pad "2" smd circle
			(at 0.40005 0)
			(size 0 0)
			(layers "F.Cu" "F.Mask" "F.Paste")
			(net "SMB_E1S_3V3AUX_ISO_SCL")
		)
	)
	(footprint ""
		(layer "F.Cu")
		(at 322.8721 -76.585064 -90)
		(property "Reference" "R2974"
			(at 0 0 270)
			(layer "F.SilkS")
			(hide yes)
			(effects
				(font
					(size 1.27 1.27)
				)
			)
		)
		(property "Value" ""
			(at 0 0 270)
			(layer "F.Fab")
			(effects
				(font
					(size 1.27 1.27)
				)
			)
		)
		(duplicate_pad_numbers_are_jumpers no)
		(fp_line
			(start -0.7874 0.4064)
			(end -0.7874 -0.4064)
			(stroke
				(width 0.1524)
				(type default)
			)
			(layer "F.SilkS")
		)
		(fp_line
			(start 0.7874 0.4064)
			(end -0.7874 0.4064)
			(stroke
				(width 0.1524)
				(type default)
			)
			(layer "F.SilkS")
		)
		(fp_line
			(start -0.7874 -0.4064)
			(end 0.7874 -0.4064)
			(stroke
				(width 0.1524)
				(type default)
			)
			(layer "F.SilkS")
		)
		(fp_line
			(start 0.7874 -0.4064)
			(end 0.7874 0.4064)
			(stroke
				(width 0.1524)
				(type default)
			)
			(layer "F.SilkS")
		)
		(fp_line
			(start -0.67945 0.3048)
			(end -0.67945 -0.305054)
			(stroke
				(width 0.1)
				(type default)
			)
			(layer "F.Fab")
		)
		(fp_line
			(start -0.12065 0.3048)
			(end -0.67945 0.3048)
			(stroke
				(width 0.1)
				(type default)
			)
			(layer "F.Fab")
		)
		(fp_line
			(start 0.120396 0.3048)
			(end 0.120396 0.2794)
			(stroke
				(width 0.1)
				(type default)
			)
			(layer "F.Fab")
		)
		(fp_line
			(start 0.67945 0.3048)
			(end 0.120396 0.3048)
			(stroke
				(width 0.1)
				(type default)
			)
			(layer "F.Fab")
		)
		(fp_line
			(start -0.12065 0.2794)
			(end -0.12065 0.3048)
			(stroke
				(width 0.1)
				(type default)
			)
			(layer "F.Fab")
		)
		(fp_line
			(start 0.120396 0.2794)
			(end -0.12065 0.2794)
			(stroke
				(width 0.1)
				(type default)
			)
			(layer "F.Fab")
		)
		(fp_line
			(start -0.12065 -0.2794)
			(end 0.12065 -0.2794)
			(stroke
				(width 0.1)
				(type default)
			)
			(layer "F.Fab")
		)
		(fp_line
			(start 0.12065 -0.2794)
			(end 0.12065 -0.3048)
			(stroke
				(width 0.1)
				(type default)
			)
			(layer "F.Fab")
		)
		(fp_line
			(start 0.12065 -0.3048)
			(end 0.67945 -0.3048)
			(stroke
				(width 0.1)
				(type default)
			)
			(layer "F.Fab")
		)
		(fp_line
			(start 0.67945 -0.3048)
			(end 0.67945 0.3048)
			(stroke
				(width 0.1)
				(type default)
			)
			(layer "F.Fab")
		)
		(fp_line
			(start -0.67945 -0.305054)
			(end -0.12065 -0.305054)
			(stroke
				(width 0.1)
				(type default)
			)
			(layer "F.Fab")
		)
		(fp_line
			(start -0.12065 -0.305054)
			(end -0.12065 -0.2794)
			(stroke
				(width 0.1)
				(type default)
			)
			(layer "F.Fab")
		)
		(pad "1" smd circle
			(at -0.40005 0 270)
			(size 0 0)
			(layers "F.Cu" "F.Mask" "F.Paste")
			(net "P1V05_PCH_AUX")
		)
		(pad "2" smd circle
			(at 0.40005 0 270)
			(size 0 0)
			(layers "F.Cu" "F.Mask" "F.Paste")
			(net "FAB_REV_ID1")
		)
	)
)
